# TIMECARD (Time Appliance Project (Time Card)) — schematic netlist excerpt (pin names and nets, part order shuffled) for the footprints in the layout excerpt that follows; sources: Cadence DE-HDL packaged netlist, KiCad conversion of R4006-B0001-02_R01.brd

Q2  POWERMOS_3P_NCH_V1  pkg SOT23_V1_H044  page 21
  G  = USB_PWR_EN
  S  = SG
  D  = UNNAMED_527_POWERMOS3PNCHV1_I23

(kicad_pcb
	(version 20260206)
	(generator "pcbnew")
	(generator_version "10.0")
	(general
		(thickness 1.6)
		(legacy_teardrops no)
	)
	(paper "A4")
	(title_block
		(title "timecard-production-celestica-r4006 — R4006-B0001-02_R01.brd")
		(comment 1 "Time Appliance Project (Time Card) / footprints 799-799 of 1113")
	)
	(layers
		(0 "F.Cu" signal "TOP")
		(4 "In1.Cu" signal "L02_GND1")
		(6 "In2.Cu" signal "L03_SIG1")
		(8 "In3.Cu" signal "L04_GND2")
		(10 "In4.Cu" signal "L05_VCC1")
		(12 "In5.Cu" signal "L06_VCC2")
		(14 "In6.Cu" signal "L07_GND3")
		(16 "In7.Cu" signal "L08_SIG2")
		(18 "In8.Cu" signal "L09_GND4")
		(2 "B.Cu" signal "BOTTOM")
		(9 "F.Adhes" user "F.Adhesive")
		(11 "B.Adhes" user "B.Adhesive")
		(13 "F.Paste" user "Package Geometry/Pastemask Top")
		(15 "B.Paste" user "Package Geometry/Pastemask Bottom")
		(5 "F.SilkS" user "Ref Des/Silkscreen Top")
		(7 "B.SilkS" user "Ref Des/Silkscreen Bottom")
		(1 "F.Mask" user "Board Geometry/Soldermask Top")
		(3 "B.Mask" user "Board Geometry/Soldermask Bottom")
		(17 "Dwgs.User" user "User.Drawings")
		(19 "Cmts.User" user "User.Comments")
		(21 "Eco1.User" user "User.Eco1")
		(23 "Eco2.User" user "User.Eco2")
		(25 "Edge.Cuts" user "Board Geometry/Outline")
		(27 "Margin" user)
		(31 "F.CrtYd" user "Package Geometry/Place Bound Top")
		(29 "B.CrtYd" user "Package Geometry/Place Bound Bottom")
		(35 "F.Fab" user "Ref Des/Assembly Top")
		(33 "B.Fab" user "Ref Des/Assembly Bottom")
	)
	(footprint ""
		(layer "B.Cu")
		(at 76.454 -55.372 90)
		(property "Reference" "Q2"
			(at 0 3.77063 270)
			(unlocked yes)
			(layer "B.SilkS")
			(effects
				(font
					(size 0.7874 0.5842)
					(thickness 0.1524)
				)
				(justify mirror)
			)
		)
		(property "Value" ""
			(at 0 0 90)
			(layer "B.Fab")
			(effects
				(font
					(size 1.27 1.27)
				)
				(justify mirror)
			)
		)
		(property "User Part Number" "PARTNUM*"
			(at 0.074676 4.841748 90)
			(unlocked yes)
			(layer "Cmts.User")
			(hide yes)
			(effects
				(font
					(size 0.7874 0.5842)
					(thickness 0.000001)
				)
				(justify mirror)
			)
		)
		(property "Device Type" "POWERMOS_3P_NCH_V1-G121-10200-A"
			(at 0.051562 3.91414 90)
			(unlocked yes)
			(layer "B.Fab")
			(hide yes)
			(effects
				(font
					(size 0.7874 0.5842)
					(thickness 0.000001)
				)
				(justify mirror)
			)
		)
		(duplicate_pad_numbers_are_jumpers no)
		(fp_line
			(start 0.7493 -2.0574)
			(end -0.7493 -2.0574)
			(stroke
				(width 0.1)
				(type default)
			)
			(layer "B.SilkS")
		)
		(fp_line
			(start -0.7493 -2.0574)
			(end -0.7493 -0.9144)
			(stroke
				(width 0.1)
				(type default)
			)
			(layer "B.SilkS")
		)
		(fp_line
			(start 1.7018 -0.9144)
			(end 0.7493 -0.9144)
			(stroke
				(width 0.1)
				(type default)
			)
			(layer "B.SilkS")
		)
		(fp_line
			(start 0.7493 -0.9144)
			(end 0.7493 -2.0574)
			(stroke
				(width 0.1)
				(type default)
			)
			(layer "B.SilkS")
		)
		(fp_line
			(start -0.7493 -0.9144)
			(end -1.7018 -0.9144)
			(stroke
				(width 0.1)
				(type default)
			)
			(layer "B.SilkS")
		)
		(fp_line
			(start -1.7018 -0.9144)
			(end -1.7018 2.0574)
			(stroke
				(width 0.1)
				(type default)
			)
			(layer "B.SilkS")
		)
		(fp_line
			(start 0.1905 0.9144)
			(end 0.1905 2.0574)
			(stroke
				(width 0.1)
				(type default)
			)
			(layer "B.SilkS")
		)
		(fp_line
			(start -0.1905 0.9144)
			(end 0.1905 0.9144)
			(stroke
				(width 0.1)
				(type default)
			)
			(layer "B.SilkS")
		)
		(fp_line
			(start 1.7018 2.0574)
			(end 1.7018 -0.9144)
			(stroke
				(width 0.1)
				(type default)
			)
			(layer "B.SilkS")
		)
		(fp_line
			(start 0.1905 2.0574)
			(end 1.7018 2.0574)
			(stroke
				(width 0.1)
				(type default)
			)
			(layer "B.SilkS")
		)
		(fp_line
			(start -0.1905 2.0574)
			(end -0.1905 0.9144)
			(stroke
				(width 0.1)
				(type default)
			)
			(layer "B.SilkS")
		)
		(fp_line
			(start -1.7018 2.0574)
			(end -0.1905 2.0574)
			(stroke
				(width 0.1)
				(type default)
			)
			(layer "B.SilkS")
		)
		(fp_poly
			(pts
				(arc
					(start 1.27 2.921)
					(mid 1.27 2.159)
					(end 1.27 2.921)
				)
			)
			(stroke
				(width 0)
				(type default)
			)
			(fill yes)
			(layer "B.SilkS")
		)
		(fp_poly
			(pts
				(xy 1.7018 2.0828) (xy 1.7018 -0.9144) (xy 0.762 -0.9144) (xy 0.762 -2.0574) (xy -0.762 -2.0574)
				(xy -0.762 -0.9144) (xy -1.7018 -0.9144) (xy -1.7018 2.0828)
			)
			(stroke
				(width 0)
				(type default)
			)
			(fill no)
			(layer "B.CrtYd")
		)
		(fp_line
			(start 0.2286 -1.143)
			(end -0.2286 -1.143)
			(stroke
				(width 0.1)
				(type default)
			)
			(layer "B.Fab")
		)
		(fp_line
			(start -0.2286 -1.143)
			(end -0.2286 -0.6604)
			(stroke
				(width 0.1)
				(type default)
			)
			(layer "B.Fab")
		)
		(fp_line
			(start 0.2286 -0.9144)
			(end -0.2286 -0.9144)
			(stroke
				(width 0.1)
				(type default)
			)
			(layer "B.Fab")
		)
		(fp_line
			(start 1.4478 -0.6604)
			(end -1.4478 -0.6604)
			(stroke
				(width 0.1)
				(type default)
			)
			(layer "B.Fab")
		)
		(fp_line
			(start 1.4478 -0.6604)
			(end 1.3716 -0.5842)
			(stroke
				(width 0.1)
				(type default)
			)
			(layer "B.Fab")
		)
		(fp_line
			(start 0.2286 -0.6604)
			(end 0.2286 -1.143)
			(stroke
				(width 0.1)
				(type default)
			)
			(layer "B.Fab")
		)
		(fp_line
			(start -0.2286 -0.6604)
			(end 0.2286 -0.6604)
			(stroke
				(width 0.1)
				(type default)
			)
			(layer "B.Fab")
		)
		(fp_line
			(start -1.4478 -0.6604)
			(end -1.4478 0.6604)
			(stroke
				(width 0.1)
				(type default)
			)
			(layer "B.Fab")
		)
		(fp_line
			(start 1.3716 -0.5842)
			(end -1.3716 -0.5842)
			(stroke
				(width 0.1)
				(type default)
			)
			(layer "B.Fab")
		)
		(fp_line
			(start -1.3716 -0.5842)
			(end -1.4478 -0.6604)
			(stroke
				(width 0.1)
				(type default)
			)
			(layer "B.Fab")
		)
		(fp_line
			(start -1.3716 -0.5842)
			(end -1.3716 0.5842)
			(stroke
				(width 0.1)
				(type default)
			)
			(layer "B.Fab")
		)
		(fp_line
			(start 1.3716 0.5842)
			(end 1.3716 -0.5842)
			(stroke
				(width 0.1)
				(type default)
			)
			(layer "B.Fab")
		)
		(fp_line
			(start -1.3716 0.5842)
			(end 1.3716 0.5842)
			(stroke
				(width 0.1)
				(type default)
			)
			(layer "B.Fab")
		)
		(fp_line
			(start -1.3716 0.5842)
			(end -1.4478 0.6604)
			(stroke
				(width 0.1)
				(type default)
			)
			(layer "B.Fab")
		)
		(fp_line
			(start 1.4478 0.6604)
			(end 1.4478 -0.6604)
			(stroke
				(width 0.1)
				(type default)
			)
			(layer "B.Fab")
		)
		(fp_line
			(start 1.4478 0.6604)
			(end 1.3716 0.5842)
			(stroke
				(width 0.1)
				(type default)
			)
			(layer "B.Fab")
		)
		(fp_line
			(start 1.1684 0.6604)
			(end 0.7112 0.6604)
			(stroke
				(width 0.1)
				(type default)
			)
			(layer "B.Fab")
		)
		(fp_line
			(start 0.7112 0.6604)
			(end 0.7112 1.143)
			(stroke
				(width 0.1)
				(type default)
			)
			(layer "B.Fab")
		)
		(fp_line
			(start -0.7112 0.6604)
			(end -1.1684 0.6604)
			(stroke
				(width 0.1)
				(type default)
			)
			(layer "B.Fab")
		)
		(fp_line
			(start -1.1684 0.6604)
			(end -1.1684 1.143)
			(stroke
				(width 0.1)
				(type default)
			)
			(layer "B.Fab")
		)
		(fp_line
			(start -1.4478 0.6604)
			(end 1.4478 0.6604)
			(stroke
				(width 0.1)
				(type default)
			)
			(layer "B.Fab")
		)
		(fp_line
			(start 1.1684 0.9144)
			(end 0.7112 0.9144)
			(stroke
				(width 0.1)
				(type default)
			)
			(layer "B.Fab")
		)
		(fp_line
			(start -0.7112 0.9144)
			(end -1.1684 0.9144)
			(stroke
				(width 0.1)
				(type default)
			)
			(layer "B.Fab")
		)
		(fp_line
			(start 1.1684 1.143)
			(end 1.1684 0.6604)
			(stroke
				(width 0.1)
				(type default)
			)
			(layer "B.Fab")
		)
		(fp_line
			(start 0.7112 1.143)
			(end 1.1684 1.143)
			(stroke
				(width 0.1)
				(type default)
			)
			(layer "B.Fab")
		)
		(fp_line
			(start -0.7112 1.143)
			(end -0.7112 0.6604)
			(stroke
				(width 0.1)
				(type default)
			)
			(layer "B.Fab")
		)
		(fp_line
			(start -1.1684 1.143)
			(end -0.7112 1.143)
			(stroke
				(width 0.1)
				(type default)
			)
			(layer "B.Fab")
		)
		(fp_poly
			(pts
				(arc
					(start 1.016 2.794)
					(mid 1.016 2.032)
					(end 1.016 2.794)
				)
			)
			(stroke
				(width 0)
				(type default)
			)
			(fill yes)
			(layer "B.Fab")
		)
		(fp_text user "2"
			(at -1.42875 2.667 0)
			(unlocked yes)
			(layer "B.SilkS")
			(effects
				(font
					(size 0.635 0.4064)
					(thickness 0.1524)
				)
				(justify mirror)
			)
		)
		(fp_text user "2"
			(at -1.05537 2.54 0)
			(unlocked yes)
			(layer "B.Fab")
			(effects
				(font
					(size 0.7874 0.5842)
					(thickness 0.1524)
				)
				(justify mirror)
			)
		)
		(pad "1" smd rect
			(at 0.9398 1.1049 270)
			(size 0.9906 1.397)
			(layers "B.Cu" "B.Mask" "B.Paste")
			(net "USB_PWR_EN")
		)
		(pad "2" smd rect
			(at -0.9398 1.1049 270)
			(size 0.9906 1.397)
			(layers "B.Cu" "B.Mask" "B.Paste")
			(net "SG")
		)
		(pad "3" smd rect
			(at 0 -1.1049 270)
			(size 0.9906 1.397)
			(layers "B.Cu" "B.Mask" "B.Paste")
			(net "UNNAMED_527_POWERMOS3PNCHV1_I23")
		)
	)
)
